FILE_TYPE = MACRO_DRAWING;
SET COLOR_WIRE YELLOW;
SET COLOR_PROP ORANGE;
SET COLOR_DOT WHITE;
SET COLOR_ARC YELLOW;
SET COLOR_BODY GREEN;
SET COLOR_NOTE PURPLE;
SET PROP_DISPLAY VALUE;
SET PAGE_NUMBER P238;
FORCEADD QUANTA_TITLE_BLOCK_C..1
(625 7925);
FORCEPROP 1 LAST Q_TITLE BLANK
J 0
(-8691 7976);
DISPLAY 2.446809 (-8691 7976);
PAINT GREEN (-8691 7976);
FORCEPROP 2 LAST CUSTOM_TXT_CDS <NAME_2>
J 0
(-2550 7975);
FORCEPROP 2 LAST CUSTOM_TXT_CDS <Q_NUMBER>
J 0
(-778 8028);
DISPLAY 1.212766 (-778 8028);
FORCEPROP 2 LAST CUSTOM_TXT_CDS <Q_PROJ>
J 0
(-1757 8027);
DISPLAY 1.212766 (-1757 8027);
FORCEPROP 2 LAST CUSTOM_TXT_CDS <CON_PAGE_NUM> OF <CON_TOTAL_PAGES>
J 0
(179 7943);
DISPLAY 0.978723 (179 7943);
FORCEPROP 2 LAST CUSTOM_TXT_CDS <Q_REV>
J 0
(441 8028);
DISPLAY 1.212766 (441 8028);
FORCEPROP 2 LAST CUSTOM_TXT_CDS <NAME_1>
J 0
(-2550 8100);
FORCEPROP 2 LAST CUSTOM_TXT_CDS <CON_LAST_MODIFIED>
J 0
(-1260 7940);
DISPLAY 0.978723 (-1260 7940);
FORCEPROP 1 LAST Q_DEPT 
J 1
(-3138 7974);
DISPLAY 1.957447 (-3138 7974);
PAINT GREEN (-3138 7974);
FORCEPROP 2 LAST CDS_XR_PAGE_TITLE CR-249 : @S9S_MB_2U_LIB.S9S_MB_2U(SCH_1):PAGE249
J 0
(-7265 13175);
DISPLAY 0.638298 (-7265 13175);
PAINT PINK (-7265 13175);
DISPLAY INVISIBLE (-7265 13175);
FORCEPROP 2 LAST PAGE_BORDER TRUE
J 0
(-7265 13175);
DISPLAY 0.638298 (-7265 13175);
PAINT PINK (-7265 13175);
DISPLAY INVISIBLE (-7265 13175);
FORCEPROP 1 LAST COMMENT_BODY TRUE
J 0
(637 7912);
DISPLAY 0.978723 (637 7912);
PAINT GREEN (637 7912);
DISPLAY INVISIBLE (637 7912);
FORCEPROP 1 LAST CDS_LMAN_SYM_OUTLINE -9475,6775,100,-125
J 0
(625 7925);
DISPLAY 0.468085 (625 7925);
PAINT GREEN (625 7925);
DISPLAY INVISIBLE (625 7925);
FORCEPROP 2 LAST CDS_LIB pure_quanta
J 0
(625 7925);
DISPLAY INVISIBLE (625 7925);
FORCEPROP 2 LAST CUSTOM_TXT_CDS <XR_PAGE_TITLE>
J 0
(-7265 13175);
DISPLAY 0.638298 (-7265 13175);
PAINT PINK (-7265 13175);
DISPLAY INVISIBLE (-7265 13175);
FORCEPROP 0 LAST CDS_CON_LAST_MODIFIED Thu Aug 24 16:16:03 2023
J 0
(-1260 7940);
DISPLAY INVISIBLE (-1260 7940);
FORCENOTE
THIS PAGE WAS INTENTIONALLY LEFT BLANK
(-8625 11350) 0;
DISPLAY LEFT (-8625 11350);
DISPLAY 4.914894 (-8625 11350);
QUIT
